(kicad_pcb
	(version 20241229)
	(generator "pcbnew")
	(generator_version "9.0")
	(general
		(thickness 1.711)
		(legacy_teardrops no)
	)
	(paper "A4")
	(title_block
		(title "Antmicro Baseboard for Jetson AGX Thor")
		(date "2026-02-18")
		(rev "1.1.0")
		(company "Antmicro Ltd")
		(comment 1 "www.antmicro.com")
		(comment 9 "footprints 61-64 of 1170")
	)
	(layers
		(0 "F.Cu" signal)
		(4 "In1.Cu" signal)
		(6 "In2.Cu" signal)
		(8 "In3.Cu" signal)
		(10 "In4.Cu" jumper)
		(12 "In5.Cu" signal)
		(14 "In6.Cu" signal)
		(16 "In7.Cu" signal)
		(18 "In8.Cu" signal)
		(2 "B.Cu" signal)
		(9 "F.Adhes" user "F.Adhesive")
		(11 "B.Adhes" user "B.Adhesive")
		(13 "F.Paste" user)
		(15 "B.Paste" user)
		(5 "F.SilkS" user "F.Silkscreen")
		(7 "B.SilkS" user "B.Silkscreen")
		(1 "F.Mask" user)
		(3 "B.Mask" user)
		(17 "Dwgs.User" user "User.Drawings")
		(19 "Cmts.User" user "User.Comments")
		(21 "Eco1.User" user "User.Eco1")
		(23 "Eco2.User" user "User.Eco2")
		(25 "Edge.Cuts" user)
		(27 "Margin" user)
		(31 "F.CrtYd" user "F.Courtyard")
		(29 "B.CrtYd" user "B.Courtyard")
		(35 "F.Fab" user)
		(33 "B.Fab" user)
	)
	(footprint "antmicro-footprints:LED_0603_1608Metric_G"
		(layer "F.Cu")
		(at 179.75 55.35 -90)
		(descr "LED SMD 0603 Green")
		(tags "LED SMD 0603 Green")
		(property "Reference" "D10"
			(at -0.89 1.51 90)
			(layer "F.SilkS")
			(effects
				(font
					(size 0.7 0.7)
					(thickness 0.15)
				)
				(justify right top)
			)
		)
		(property "Value" "LED_G_0603_LTST-C190GKT"
			(at -0.001 1.599 90)
			(layer "F.Fab")
			(effects
				(font
					(size 0.7 0.7)
					(thickness 0.15)
				)
				(justify right top)
			)
		)
		(property "Datasheet" "https://media.digikey.com/pdf/Data%20Sheets/Lite-On%20PDFs/LTST-C190GKT.pdf"
			(at 0 0 90)
			(layer "F.Fab")
			(hide yes)
			(effects
				(font
					(size 1.27 1.27)
					(thickness 0.15)
				)
			)
		)
		(property "Description" "LED, Green, SMD, 0603, 20 mA, 2.1 V, 569 nm"
			(at 0 0 90)
			(layer "F.Fab")
			(hide yes)
			(effects
				(font
					(size 1.27 1.27)
					(thickness 0.15)
				)
			)
		)
		(property "MPN" "LTST-C190GKT"
			(at 0 0 270)
			(unlocked yes)
			(layer "F.Fab")
			(hide yes)
			(effects
				(font
					(size 1 1)
					(thickness 0.15)
				)
			)
		)
		(property "Manufacturer" "Lite-On"
			(at 0 0 270)
			(unlocked yes)
			(layer "F.Fab")
			(hide yes)
			(effects
				(font
					(size 1 1)
					(thickness 0.15)
				)
			)
		)
		(property "Author" "Antmicro"
			(at 0 0 270)
			(unlocked yes)
			(layer "F.Fab")
			(hide yes)
			(effects
				(font
					(size 1 1)
					(thickness 0.15)
				)
			)
		)
		(property "License" "Apache-2.0"
			(at 0 0 270)
			(unlocked yes)
			(layer "F.Fab")
			(hide yes)
			(effects
				(font
					(size 1 1)
					(thickness 0.15)
				)
			)
		)
		(property "Color" "Green"
			(at 0 0 270)
			(unlocked yes)
			(layer "F.Fab")
			(hide yes)
			(effects
				(font
					(size 1 1)
					(thickness 0.15)
				)
			)
		)
		(sheetname "/Power/")
		(sheetfile "power.kicad_sch")
		(attr smd)
		(fp_line
			(start 0.22 0.35)
			(end -0.22 0.35)
			(stroke
				(width 0.15)
				(type solid)
			)
			(layer "F.SilkS")
		)
		(fp_line
			(start -0.094672 0.201008)
			(end -0.094672 -0.198992)
			(stroke
				(width 0.1)
				(type solid)
			)
			(layer "F.SilkS")
		)
		(fp_line
			(start 0.105328 0.201008)
			(end -0.094672 0.001008)
			(stroke
				(width 0.1)
				(type solid)
			)
			(layer "F.SilkS")
		)
		(fp_line
			(start 0.105328 0.201008)
			(end 0.105328 -0.198992)
			(stroke
				(width 0.1)
				(type solid)
			)
			(layer "F.SilkS")
		)
		(fp_line
			(start -0.094672 0.001008)
			(end -0.24 0.001008)
			(stroke
				(width 0.1)
				(type solid)
			)
			(layer "F.SilkS")
		)
		(fp_line
			(start -0.094672 0.001008)
			(end 0.105328 -0.198992)
			(stroke
				(width 0.1)
				(type solid)
			)
			(layer "F.SilkS")
		)
		(fp_line
			(start 0.105328 0.001008)
			(end 0.24 0.001)
			(stroke
				(width 0.1)
				(type solid)
			)
			(layer "F.SilkS")
		)
		(fp_line
			(start -1.18 -0.319)
			(end -1.18 0.321)
			(stroke
				(width 0.15)
				(type solid)
			)
			(layer "F.SilkS")
		)
		(fp_line
			(start 0.22 -0.35)
			(end -0.22 -0.35)
			(stroke
				(width 0.15)
				(type solid)
			)
			(layer "F.SilkS")
		)
		(fp_rect
			(start 1.25 0.65)
			(end -1.25 -0.65)
			(stroke
				(width 0.05)
				(type solid)
			)
			(fill no)
			(layer "F.CrtYd")
		)
		(fp_line
			(start -0.199 0.2)
			(end -0.199 0.1)
			(stroke
				(width 0.15)
				(type solid)
			)
			(layer "F.Fab")
		)
		(fp_line
			(start 0.201 0.2)
			(end 0.201 0)
			(stroke
				(width 0.15)
				(type solid)
			)
			(layer "F.Fab")
		)
		(fp_line
			(start -0.199 0)
			(end -0.597 0)
			(stroke
				(width 0.15)
				(type solid)
			)
			(layer "F.Fab")
		)
		(fp_line
			(start -0.101 0)
			(end 0.201 0.2)
			(stroke
				(width 0.15)
				(type solid)
			)
			(layer "F.Fab")
		)
		(fp_line
			(start 0.201 0)
			(end 0.201 -0.202)
			(stroke
				(width 0.15)
				(type solid)
			)
			(layer "F.Fab")
		)
		(fp_line
			(start 0.599 0)
			(end 0.201 0)
			(stroke
				(width 0.15)
				(type solid)
			)
			(layer "F.Fab")
		)
		(fp_line
			(start -0.199 -0.202)
			(end -0.199 0.1)
			(stroke
				(width 0.15)
				(type solid)
			)
			(layer "F.Fab")
		)
		(fp_line
			(start 0.201 -0.202)
			(end -0.101 0)
			(stroke
				(width 0.15)
				(type solid)
			)
			(layer "F.Fab")
		)
		(fp_rect
			(start 0.848 0.4)
			(end -0.85 -0.402)
			(stroke
				(width 0.15)
				(type solid)
			)
			(fill no)
			(layer "F.Fab")
		)
		(fp_text user "${REFERENCE}"
			(at -1.4224 5.999 90)
			(layer "F.Fab")
			(effects
				(font
					(size 0.7 0.7)
					(thickness 0.15)
				)
				(justify right top)
			)
		)
		(fp_text user "Author: Antmicro"
			(at -1.4224 4.799 90)
			(layer "F.Fab")
			(effects
				(font
					(size 0.7 0.7)
					(thickness 0.15)
				)
				(justify right top)
			)
		)
		(fp_text user "License: Apache-2.0"
			(at -1.4224 3.599 90)
			(layer "F.Fab")
			(effects
				(font
					(size 0.7 0.7)
					(thickness 0.15)
				)
				(justify right top)
			)
		)
		(pad "1" smd roundrect
			(at -0.7 0 90)
			(size 0.8 1)
			(layers "F.Cu" "F.Mask" "F.Paste")
			(roundrect_rratio 0.2)
			(net 1 "GND")
			(pinfunction "C")
			(pintype "passive")
		)
		(pad "2" smd roundrect
			(at 0.7 0 90)
			(size 0.8 1)
			(layers "F.Cu" "F.Mask" "F.Paste")
			(roundrect_rratio 0.2)
			(net 529 "Net-(D10-A)")
			(pinfunction "A")
			(pintype "passive")
		)
	)
	(footprint "antmicro-footprints:C_0402_1005Metric"
		(layer "F.Cu")
		(at 179.375 107.916)
		(descr "Capacitor SMD 0402")
		(tags "capacitor SMD 0402")
		(property "Reference" "C59"
			(at -3.115 -0.03 0)
			(layer "F.SilkS")
			(effects
				(font
					(size 0.7 0.7)
					(thickness 0.15)
				)
				(justify left bottom)
			)
		)
		(property "Value" "C_100n_0402"
			(at -1.022927 2.155213 0)
			(layer "F.Fab")
			(effects
				(font
					(size 0.7 0.7)
					(thickness 0.15)
				)
				(justify left bottom)
			)
		)
		(property "Datasheet" "https://www.murata.com/products/productdetail?partno=GRM155R61H104KE14%23"
			(at 0 0 0)
			(layer "F.Fab")
			(hide yes)
			(effects
				(font
					(size 1.27 1.27)
					(thickness 0.15)
				)
			)
		)
		(property "Description" "SMD Multilayer Ceramic Capacitor, 0.1 µF, 50 V, 0402 [1005 Metric], ± 10%, X5R, GRM Series"
			(at 0 0 0)
			(layer "F.Fab")
			(hide yes)
			(effects
				(font
					(size 1.27 1.27)
					(thickness 0.15)
				)
			)
		)
		(property "Manufacturer" "Murata"
			(at 0 0 0)
			(unlocked yes)
			(layer "F.Fab")
			(hide yes)
			(effects
				(font
					(size 1 1)
					(thickness 0.15)
				)
			)
		)
		(property "MPN" "GRM155R61H104KE14D"
			(at 0 0 0)
			(unlocked yes)
			(layer "F.Fab")
			(hide yes)
			(effects
				(font
					(size 1 1)
					(thickness 0.15)
				)
			)
		)
		(property "Val" "100n"
			(at 0 0 0)
			(unlocked yes)
			(layer "F.Fab")
			(hide yes)
			(effects
				(font
					(size 1 1)
					(thickness 0.15)
				)
			)
		)
		(property "License" "Apache-2.0"
			(at 0 0 0)
			(unlocked yes)
			(layer "F.Fab")
			(hide yes)
			(effects
				(font
					(size 1 1)
					(thickness 0.15)
				)
			)
		)
		(property "Author" "Antmicro"
			(at 0 0 0)
			(unlocked yes)
			(layer "F.Fab")
			(hide yes)
			(effects
				(font
					(size 1 1)
					(thickness 0.15)
				)
			)
		)
		(property "Voltage" "50V"
			(at 0 0 0)
			(unlocked yes)
			(layer "F.Fab")
			(hide yes)
			(effects
				(font
					(size 1 1)
					(thickness 0.15)
				)
			)
		)
		(property "Dielectric" "X5R"
			(at 0 0 0)
			(unlocked yes)
			(layer "F.Fab")
			(hide yes)
			(effects
				(font
					(size 1 1)
					(thickness 0.15)
				)
			)
		)
		(sheetname "/DCDC/")
		(sheetfile "dcdc.kicad_sch")
		(attr smd)
		(fp_rect
			(start -0.925 -0.47)
			(end 0.925 0.47)
			(stroke
				(width 0.05)
				(type default)
			)
			(fill no)
			(layer "F.CrtYd")
		)
		(fp_line
			(start -0.494 -0.25)
			(end 0.504 -0.25)
			(stroke
				(width 0.15)
				(type solid)
			)
			(layer "F.Fab")
		)
		(fp_line
			(start -0.494 0.248)
			(end -0.494 -0.25)
			(stroke
				(width 0.15)
				(type solid)
			)
			(layer "F.Fab")
		)
		(fp_line
			(start 0.504 -0.25)
			(end 0.504 0.248)
			(stroke
				(width 0.15)
				(type solid)
			)
			(layer "F.Fab")
		)
		(fp_line
			(start 0.504 0.248)
			(end -0.494 0.248)
			(stroke
				(width 0.15)
				(type solid)
			)
			(layer "F.Fab")
		)
		(fp_text user "Author: Antmicro"
			(at -0.939 3.399 0)
			(layer "F.Fab")
			(effects
				(font
					(size 0.7 0.7)
					(thickness 0.15)
				)
				(justify left bottom)
			)
		)
		(fp_text user "License: Apache-2.0"
			(at -0.939 5.799 0)
			(layer "F.Fab")
			(effects
				(font
					(size 0.7 0.7)
					(thickness 0.15)
				)
				(justify left bottom)
			)
		)
		(fp_text user "${REFERENCE}"
			(at -0.939 4.599 0)
			(layer "F.Fab")
			(effects
				(font
					(size 0.7 0.7)
					(thickness 0.15)
				)
				(justify left bottom)
			)
		)
		(pad "1" smd roundrect
			(at -0.48 0)
			(size 0.59 0.64)
			(layers "F.Cu" "F.Mask" "F.Paste")
			(roundrect_rratio 0.25)
			(net 26 "/DCDC/5V_PHASE")
			(pintype "passive")
		)
		(pad "2" smd roundrect
			(at 0.48 0)
			(size 0.59 0.64)
			(layers "F.Cu" "F.Mask" "F.Paste")
			(roundrect_rratio 0.25)
			(net 25 "/DCDC/5V_BOOT")
			(pintype "passive")
		)
	)
	(footprint "antmicro-footprints:C_0402_1005Metric"
		(layer "F.Cu")
		(at 182.84 71.45 -90)
		(descr "Capacitor SMD 0402")
		(tags "capacitor SMD 0402")
		(property "Reference" "C280"
			(at -0.9 -0.75 90)
			(layer "F.SilkS")
			(effects
				(font
					(size 0.7 0.7)
					(thickness 0.15)
				)
				(justify right top)
			)
		)
		(property "Value" "C_4u7_25V_0402"
			(at -1.022927 2.155213 90)
			(layer "F.Fab")
			(effects
				(font
					(size 0.7 0.7)
					(thickness 0.15)
				)
				(justify right top)
			)
		)
		(property "Datasheet" "https://www.murata.com/products/productdetail?partno=GRM155C61E475ME15%23"
			(at 0 0 90)
			(layer "F.Fab")
			(hide yes)
			(effects
				(font
					(size 1.27 1.27)
					(thickness 0.15)
				)
			)
		)
		(property "Description" "SMD Multilayer Ceramic Capacitor"
			(at 0 0 90)
			(layer "F.Fab")
			(hide yes)
			(effects
				(font
					(size 1.27 1.27)
					(thickness 0.15)
				)
			)
		)
		(property "MPN" "GRM155C61E475ME15J"
			(at 0 0 270)
			(unlocked yes)
			(layer "F.Fab")
			(hide yes)
			(effects
				(font
					(size 1 1)
					(thickness 0.15)
				)
			)
		)
		(property "Manufacturer" "Murata"
			(at 0 0 270)
			(unlocked yes)
			(layer "F.Fab")
			(hide yes)
			(effects
				(font
					(size 1 1)
					(thickness 0.15)
				)
			)
		)
		(property "License" "Apache-2.0"
			(at 0 0 270)
			(unlocked yes)
			(layer "F.Fab")
			(hide yes)
			(effects
				(font
					(size 1 1)
					(thickness 0.15)
				)
			)
		)
		(property "Author" "Antmicro"
			(at 0 0 270)
			(unlocked yes)
			(layer "F.Fab")
			(hide yes)
			(effects
				(font
					(size 1 1)
					(thickness 0.15)
				)
			)
		)
		(property "Val" "4u7"
			(at 0 0 270)
			(unlocked yes)
			(layer "F.Fab")
			(hide yes)
			(effects
				(font
					(size 1 1)
					(thickness 0.15)
				)
			)
		)
		(property "Voltage" "25V"
			(at 0 0 270)
			(unlocked yes)
			(layer "F.Fab")
			(hide yes)
			(effects
				(font
					(size 1 1)
					(thickness 0.15)
				)
			)
		)
		(property "Dielectric" "X5S"
			(at 0 0 270)
			(unlocked yes)
			(layer "F.Fab")
			(hide yes)
			(effects
				(font
					(size 1 1)
					(thickness 0.15)
				)
			)
		)
		(component_classes
			(class "DCDC_20V")
		)
		(sheetname "/DCDC/")
		(sheetfile "dcdc.kicad_sch")
		(attr smd)
		(fp_rect
			(start -0.925 -0.47)
			(end 0.925 0.47)
			(stroke
				(width 0.05)
				(type default)
			)
			(fill no)
			(layer "F.CrtYd")
		)
		(fp_line
			(start -0.494 0.248)
			(end -0.494 -0.25)
			(stroke
				(width 0.15)
				(type solid)
			)
			(layer "F.Fab")
		)
		(fp_line
			(start 0.504 0.248)
			(end -0.494 0.248)
			(stroke
				(width 0.15)
				(type solid)
			)
			(layer "F.Fab")
		)
		(fp_line
			(start -0.494 -0.25)
			(end 0.504 -0.25)
			(stroke
				(width 0.15)
				(type solid)
			)
			(layer "F.Fab")
		)
		(fp_line
			(start 0.504 -0.25)
			(end 0.504 0.248)
			(stroke
				(width 0.15)
				(type solid)
			)
			(layer "F.Fab")
		)
		(fp_text user "${REFERENCE}"
			(at -0.939 4.599 90)
			(layer "F.Fab")
			(effects
				(font
					(size 0.7 0.7)
					(thickness 0.15)
				)
				(justify right top)
			)
		)
		(fp_text user "Author: Antmicro"
			(at -0.939 3.399 90)
			(layer "F.Fab")
			(effects
				(font
					(size 0.7 0.7)
					(thickness 0.15)
				)
				(justify right top)
			)
		)
		(fp_text user "License: Apache-2.0"
			(at -0.939 5.799 90)
			(layer "F.Fab")
			(effects
				(font
					(size 0.7 0.7)
					(thickness 0.15)
				)
				(justify right top)
			)
		)
		(pad "1" smd roundrect
			(at -0.48 0 270)
			(size 0.59 0.64)
			(layers "F.Cu" "F.Mask" "F.Paste")
			(roundrect_rratio 0.25)
			(net 1 "GND")
			(pintype "passive")
		)
		(pad "2" smd roundrect
			(at 0.48 0 270)
			(size 0.59 0.64)
			(layers "F.Cu" "F.Mask" "F.Paste")
			(roundrect_rratio 0.25)
			(net 1081 "/DCDC/20V_VDRV")
			(pintype "passive")
		)
	)
	(footprint "antmicro-footprints:C_0402_1005Metric"
		(layer "F.Cu")
		(at 219.564132 87.75)
		(descr "Capacitor SMD 0402")
		(tags "capacitor SMD 0402")
		(property "Reference" "C145"
			(at -1.764132 1.45 0)
			(layer "F.SilkS")
			(effects
				(font
					(size 0.7 0.7)
					(thickness 0.15)
				)
				(justify left bottom)
			)
		)
		(property "Value" "C_100n_0402"
			(at -1.022927 2.155213 0)
			(layer "F.Fab")
			(effects
				(font
					(size 0.7 0.7)
					(thickness 0.15)
				)
				(justify left bottom)
			)
		)
		(property "Datasheet" "https://www.murata.com/products/productdetail?partno=GRM155R61H104KE14%23"
			(at 0 0 0)
			(layer "F.Fab")
			(hide yes)
			(effects
				(font
					(size 1.27 1.27)
					(thickness 0.15)
				)
			)
		)
		(property "Description" "SMD Multilayer Ceramic Capacitor, 0.1 µF, 50 V, 0402 [1005 Metric], ± 10%, X5R, GRM Series"
			(at 0 0 0)
			(layer "F.Fab")
			(hide yes)
			(effects
				(font
					(size 1.27 1.27)
					(thickness 0.15)
				)
			)
		)
		(property "Manufacturer" "Murata"
			(at 0 0 0)
			(unlocked yes)
			(layer "F.Fab")
			(hide yes)
			(effects
				(font
					(size 1 1)
					(thickness 0.15)
				)
			)
		)
		(property "MPN" "GRM155R61H104KE14D"
			(at 0 0 0)
			(unlocked yes)
			(layer "F.Fab")
			(hide yes)
			(effects
				(font
					(size 1 1)
					(thickness 0.15)
				)
			)
		)
		(property "Val" "100n"
			(at 0 0 0)
			(unlocked yes)
			(layer "F.Fab")
			(hide yes)
			(effects
				(font
					(size 1 1)
					(thickness 0.15)
				)
			)
		)
		(property "License" "Apache-2.0"
			(at 0 0 0)
			(unlocked yes)
			(layer "F.Fab")
			(hide yes)
			(effects
				(font
					(size 1 1)
					(thickness 0.15)
				)
			)
		)
		(property "Author" "Antmicro"
			(at 0 0 0)
			(unlocked yes)
			(layer "F.Fab")
			(hide yes)
			(effects
				(font
					(size 1 1)
					(thickness 0.15)
				)
			)
		)
		(property "Voltage" "50V"
			(at 0 0 0)
			(unlocked yes)
			(layer "F.Fab")
			(hide yes)
			(effects
				(font
					(size 1 1)
					(thickness 0.15)
				)
			)
		)
		(property "Dielectric" "X5R"
			(at 0 0 0)
			(unlocked yes)
			(layer "F.Fab")
			(hide yes)
			(effects
				(font
					(size 1 1)
					(thickness 0.15)
				)
			)
		)
		(sheetname "/USB DP Alt mode/")
		(sheetfile "usb_dp.kicad_sch")
		(attr smd)
		(fp_rect
			(start -0.925 -0.47)
			(end 0.925 0.47)
			(stroke
				(width 0.05)
				(type default)
			)
			(fill no)
			(layer "F.CrtYd")
		)
		(fp_line
			(start -0.494 -0.25)
			(end 0.504 -0.25)
			(stroke
				(width 0.15)
				(type solid)
			)
			(layer "F.Fab")
		)
		(fp_line
			(start -0.494 0.248)
			(end -0.494 -0.25)
			(stroke
				(width 0.15)
				(type solid)
			)
			(layer "F.Fab")
		)
		(fp_line
			(start 0.504 -0.25)
			(end 0.504 0.248)
			(stroke
				(width 0.15)
				(type solid)
			)
			(layer "F.Fab")
		)
		(fp_line
			(start 0.504 0.248)
			(end -0.494 0.248)
			(stroke
				(width 0.15)
				(type solid)
			)
			(layer "F.Fab")
		)
		(fp_text user "License: Apache-2.0"
			(at -0.939 5.799 0)
			(layer "F.Fab")
			(effects
				(font
					(size 0.7 0.7)
					(thickness 0.15)
				)
				(justify left bottom)
			)
		)
		(fp_text user "Author: Antmicro"
			(at -0.939 3.399 0)
			(layer "F.Fab")
			(effects
				(font
					(size 0.7 0.7)
					(thickness 0.15)
				)
				(justify left bottom)
			)
		)
		(fp_text user "${REFERENCE}"
			(at -0.939 4.599 0)
			(layer "F.Fab")
			(effects
				(font
					(size 0.7 0.7)
					(thickness 0.15)
				)
				(justify left bottom)
			)
		)
		(pad "1" smd roundrect
			(at -0.48 0)
			(size 0.59 0.64)
			(layers "F.Cu" "F.Mask" "F.Paste")
			(roundrect_rratio 0.25)
			(net 372 "/USB DP Alt mode/USBC1_TX2_N")
			(pintype "passive")
		)
		(pad "2" smd roundrect
			(at 0.48 0)
			(size 0.59 0.64)
			(layers "F.Cu" "F.Mask" "F.Paste")
			(roundrect_rratio 0.25)
			(net 374 "/USB DP Alt mode/USBC1_CONN_TX2_N")
			(pintype "passive")
		)
	)
)
